(kicad_pcb
	(version 20260206)
	(generator "pcbnew")
	(generator_version "10.0")
	(general
		(thickness 1.6)
		(legacy_teardrops no)
	)
	(paper "A4")
	(title_block
		(title "Wiwynn_Tioga_Pass_MB.brd")
		(comment 1 "Tioga Pass / footprints 3144-3150 of 4770")
	)
	(layers
		(0 "F.Cu" signal "TOP")
		(4 "In1.Cu" signal "L2GND")
		(6 "In2.Cu" signal "L3")
		(8 "In3.Cu" signal "L4GND")
		(10 "In4.Cu" signal "L5")
		(12 "In5.Cu" signal "L6GND")
		(14 "In6.Cu" signal "L7VCC")
		(16 "In7.Cu" signal "L8VCC")
		(18 "In8.Cu" signal "L9GND")
		(20 "In9.Cu" signal "L10")
		(22 "In10.Cu" signal "L11GND")
		(24 "In11.Cu" signal "L12")
		(26 "In12.Cu" signal "L13GND")
		(2 "B.Cu" signal "BOTTOM")
		(9 "F.Adhes" user "F.Adhesive")
		(11 "B.Adhes" user "B.Adhesive")
		(13 "F.Paste" user "Package Geometry/Pastemask Top")
		(15 "B.Paste" user "Package Geometry/Pastemask Bottom")
		(5 "F.SilkS" user "Ref Des/Silkscreen Top")
		(7 "B.SilkS" user "Ref Des/Silkscreen Bottom")
		(1 "F.Mask" user "Board Geometry/Soldermask Top")
		(3 "B.Mask" user "Board Geometry/Soldermask Bottom")
		(17 "Dwgs.User" user "User.Drawings")
		(19 "Cmts.User" user "User.Comments")
		(21 "Eco1.User" user "User.Eco1")
		(23 "Eco2.User" user "User.Eco2")
		(25 "Edge.Cuts" user "Board Geometry/Outline")
		(27 "Margin" user)
		(31 "F.CrtYd" user "Package Geometry/Place Bound Top")
		(29 "B.CrtYd" user "Package Geometry/Place Bound Bottom")
		(35 "F.Fab" user "Ref Des/Assembly Top")
		(33 "B.Fab" user "Ref Des/Assembly Bottom")
	)
	(footprint ""
		(layer "B.Cu")
		(at 164.973 -81.407 90)
		(property "Reference" "C6P10"
			(at 0 0 90)
			(layer "B.SilkS")
			(hide yes)
			(effects
				(font
					(size 1.27 1.27)
				)
				(justify mirror)
			)
		)
		(property "Value" ""
			(at 0 0 90)
			(layer "B.Fab")
			(effects
				(font
					(size 1.27 1.27)
				)
				(justify mirror)
			)
		)
		(duplicate_pad_numbers_are_jumpers no)
		(fp_poly
			(pts
				(xy -0.3048 -0.1016) (xy -0.3048 0.9906) (xy 0.3048 0.9906) (xy 0.3048 -0.1016)
			)
			(stroke
				(width 0)
				(type default)
			)
			(fill no)
			(layer "B.CrtYd")
		)
		(fp_line
			(start 0.3048 -0.1016)
			(end 0.3048 0.9906)
			(stroke
				(width 0.1)
				(type default)
			)
			(layer "B.Fab")
		)
		(fp_line
			(start -0.3048 -0.1016)
			(end 0.3048 -0.1016)
			(stroke
				(width 0.1)
				(type default)
			)
			(layer "B.Fab")
		)
		(fp_line
			(start 0.3048 0.9906)
			(end -0.3048 0.9906)
			(stroke
				(width 0.1)
				(type default)
			)
			(layer "B.Fab")
		)
		(fp_line
			(start -0.3048 0.9906)
			(end -0.3048 -0.1016)
			(stroke
				(width 0.1)
				(type default)
			)
			(layer "B.Fab")
		)
		(pad "1" smd rect
			(at 0 0 270)
			(size 0.508 0.508)
			(layers "B.Cu" "B.Mask" "B.Paste")
			(net "P3V3_DB1200")
		)
		(pad "2" smd rect
			(at 0 0.889 270)
			(size 0.508 0.508)
			(layers "B.Cu" "B.Mask" "B.Paste")
			(net "GND")
		)
		(zone
			(layer "B.Cu")
			(hatch none 0.5)
			(connect_pads
				(clearance 0)
			)
			(min_thickness 0.25)
			(keepout
				(tracks allowed)
				(vias not_allowed)
				(pads allowed)
				(copperpour not_allowed)
				(footprints allowed)
			)
			(placement
				(enabled no)
				(sheetname "")
			)
			(fill
				(thermal_gap 0.5)
				(thermal_bridge_width 0.5)
				(island_removal_mode 0)
			)
			(polygon
				(pts
					(xy 165.227 -81.661) (xy 165.227 -81.153) (xy 165.608 -81.153) (xy 165.608 -81.661)
				)
			)
		)
		(zone
			(layer "B.Cu")
			(hatch none 0.5)
			(connect_pads
				(clearance 0)
			)
			(min_thickness 0.25)
			(keepout
				(tracks not_allowed)
				(vias allowed)
				(pads allowed)
				(copperpour not_allowed)
				(footprints allowed)
			)
			(placement
				(enabled no)
				(sheetname "")
			)
			(fill
				(thermal_gap 0.5)
				(thermal_bridge_width 0.5)
				(island_removal_mode 0)
			)
			(polygon
				(pts
					(xy 165.608 -81.661) (xy 165.608 -81.153) (xy 165.227 -81.153) (xy 165.227 -81.661)
				)
			)
		)
	)
	(footprint ""
		(layer "B.Cu")
		(at 95.922592 -82.001614)
		(property "Reference" "C8P6"
			(at 0 0 0)
			(layer "B.SilkS")
			(hide yes)
			(effects
				(font
					(size 1.27 1.27)
				)
				(justify mirror)
			)
		)
		(property "Value" ""
			(at 0 0 0)
			(layer "B.Fab")
			(effects
				(font
					(size 1.27 1.27)
				)
				(justify mirror)
			)
		)
		(duplicate_pad_numbers_are_jumpers no)
		(fp_poly
			(pts
				(xy 0.7239 -0.2159) (xy -0.7239 -0.2159) (xy -0.7239 1.9939) (xy 0.7239 1.9939)
			)
			(stroke
				(width 0)
				(type default)
			)
			(fill no)
			(layer "B.CrtYd")
		)
		(fp_line
			(start -0.7239 -0.2159)
			(end 0.7239 -0.2159)
			(stroke
				(width 0.1)
				(type default)
			)
			(layer "B.Fab")
		)
		(fp_line
			(start -0.7239 1.9939)
			(end -0.7239 -0.2159)
			(stroke
				(width 0.1)
				(type default)
			)
			(layer "B.Fab")
		)
		(fp_line
			(start 0.7239 -0.2159)
			(end 0.7239 1.9939)
			(stroke
				(width 0.1)
				(type default)
			)
			(layer "B.Fab")
		)
		(fp_line
			(start 0.7239 1.9939)
			(end -0.7239 1.9939)
			(stroke
				(width 0.1)
				(type default)
			)
			(layer "B.Fab")
		)
		(pad "1" smd rect
			(at 0 0 180)
			(size 1.27 1.016)
			(layers "B.Cu" "B.Mask" "B.Paste")
			(net "PVSA_CPU1")
		)
		(pad "2" smd rect
			(at 0 1.778 180)
			(size 1.27 1.016)
			(layers "B.Cu" "B.Mask" "B.Paste")
			(net "GND")
		)
		(zone
			(layer "B.Cu")
			(hatch none 0.5)
			(connect_pads
				(clearance 0)
			)
			(min_thickness 0.25)
			(keepout
				(tracks not_allowed)
				(vias allowed)
				(pads allowed)
				(copperpour not_allowed)
				(footprints allowed)
			)
			(placement
				(enabled no)
				(sheetname "")
			)
			(fill
				(thermal_gap 0.5)
				(thermal_bridge_width 0.5)
				(island_removal_mode 0)
			)
			(polygon
				(pts
					(xy 96.557592 -81.493614) (xy 95.287592 -81.493614) (xy 95.287592 -80.731614) (xy 96.557592 -80.731614)
				)
			)
		)
	)
	(footprint ""
		(layer "B.Cu")
		(at 403.568408 -92.993718 -90)
		(property "Reference" "R2N18"
			(at 0 0 90)
			(layer "B.SilkS")
			(hide yes)
			(effects
				(font
					(size 1.27 1.27)
				)
				(justify mirror)
			)
		)
		(property "Value" ""
			(at 0 0 90)
			(layer "B.Fab")
			(effects
				(font
					(size 1.27 1.27)
				)
				(justify mirror)
			)
		)
		(duplicate_pad_numbers_are_jumpers no)
		(fp_poly
			(pts
				(xy 0.2794 -0.1016) (xy -0.2794 -0.1016) (xy -0.2794 0.9906) (xy 0.2794 0.9906)
			)
			(stroke
				(width 0)
				(type default)
			)
			(fill no)
			(layer "B.CrtYd")
		)
		(fp_line
			(start -0.2794 0.9906)
			(end -0.2794 -0.1016)
			(stroke
				(width 0.1)
				(type default)
			)
			(layer "B.Fab")
		)
		(fp_line
			(start 0.2794 0.9906)
			(end -0.2794 0.9906)
			(stroke
				(width 0.1)
				(type default)
			)
			(layer "B.Fab")
		)
		(fp_line
			(start -0.2794 -0.1016)
			(end 0.2794 -0.1016)
			(stroke
				(width 0.1)
				(type default)
			)
			(layer "B.Fab")
		)
		(fp_line
			(start 0.2794 -0.1016)
			(end 0.2794 0.9906)
			(stroke
				(width 0.1)
				(type default)
			)
			(layer "B.Fab")
		)
		(pad "1" smd rect
			(at 0 0 90)
			(size 0.508 0.508)
			(layers "B.Cu" "B.Mask" "B.Paste")
			(net "FM_BOARD_SKU_ID4")
		)
		(pad "2" smd rect
			(at 0 0.889 90)
			(size 0.508 0.508)
			(layers "B.Cu" "B.Mask" "B.Paste")
			(net "GND")
		)
		(zone
			(layer "B.Cu")
			(hatch none 0.5)
			(connect_pads
				(clearance 0)
			)
			(min_thickness 0.25)
			(keepout
				(tracks not_allowed)
				(vias allowed)
				(pads allowed)
				(copperpour not_allowed)
				(footprints allowed)
			)
			(placement
				(enabled no)
				(sheetname "")
			)
			(fill
				(thermal_gap 0.5)
				(thermal_bridge_width 0.5)
				(island_removal_mode 0)
			)
			(polygon
				(pts
					(xy 402.933408 -92.739718) (xy 402.933408 -93.247718) (xy 403.314408 -93.247718) (xy 403.314408 -92.739718)
				)
			)
		)
		(zone
			(layer "B.Cu")
			(hatch none 0.5)
			(connect_pads
				(clearance 0)
			)
			(min_thickness 0.25)
			(keepout
				(tracks allowed)
				(vias not_allowed)
				(pads allowed)
				(copperpour not_allowed)
				(footprints allowed)
			)
			(placement
				(enabled no)
				(sheetname "")
			)
			(fill
				(thermal_gap 0.5)
				(thermal_bridge_width 0.5)
				(island_removal_mode 0)
			)
			(polygon
				(pts
					(xy 403.314408 -92.739718) (xy 403.314408 -93.247718) (xy 402.933408 -93.247718) (xy 402.933408 -92.739718)
				)
			)
		)
	)
	(footprint ""
		(layer "B.Cu")
		(at 474.345 -120.8278)
		(property "Reference" "R1M14"
			(at 0 0 0)
			(layer "B.SilkS")
			(hide yes)
			(effects
				(font
					(size 1.27 1.27)
				)
				(justify mirror)
			)
		)
		(property "Value" ""
			(at 0 0 0)
			(layer "B.Fab")
			(effects
				(font
					(size 1.27 1.27)
				)
				(justify mirror)
			)
		)
		(duplicate_pad_numbers_are_jumpers no)
		(fp_rect
			(start -0.2794 0.9906)
			(end 0.2794 -0.1016)
			(stroke
				(width 0)
				(type default)
			)
			(fill no)
			(layer "B.CrtYd")
		)
		(fp_line
			(start -0.2794 -0.1016)
			(end 0.2794 -0.1016)
			(stroke
				(width 0.1)
				(type default)
			)
			(layer "B.Fab")
		)
		(fp_line
			(start -0.2794 0.9906)
			(end -0.2794 -0.1016)
			(stroke
				(width 0.1)
				(type default)
			)
			(layer "B.Fab")
		)
		(fp_line
			(start 0.2794 -0.1016)
			(end 0.2794 0.9906)
			(stroke
				(width 0.1)
				(type default)
			)
			(layer "B.Fab")
		)
		(fp_line
			(start 0.2794 0.9906)
			(end -0.2794 0.9906)
			(stroke
				(width 0.1)
				(type default)
			)
			(layer "B.Fab")
		)
		(pad "1" smd rect
			(at 0 0 180)
			(size 0.508 0.508)
			(layers "B.Cu" "B.Mask" "B.Paste")
			(net "RST_PCIE_CPU_DEV0_N")
		)
		(pad "2" smd rect
			(at 0 0.889 180)
			(size 0.508 0.508)
			(layers "B.Cu" "B.Mask" "B.Paste")
			(net "RST_PCIE_CPU_DEV0_R_N")
		)
		(zone
			(layer "B.Cu")
			(hatch none 0.5)
			(connect_pads
				(clearance 0)
			)
			(min_thickness 0.25)
			(keepout
				(tracks not_allowed)
				(vias allowed)
				(pads allowed)
				(copperpour not_allowed)
				(footprints allowed)
			)
			(placement
				(enabled no)
				(sheetname "")
			)
			(fill
				(thermal_gap 0.5)
				(thermal_bridge_width 0.5)
				(island_removal_mode 0)
			)
			(polygon
				(pts
					(xy 474.091 -120.1928) (xy 474.599 -120.1928) (xy 474.599 -120.5738) (xy 474.091 -120.5738)
				)
			)
		)
		(zone
			(layer "B.Cu")
			(hatch none 0.5)
			(connect_pads
				(clearance 0)
			)
			(min_thickness 0.25)
			(keepout
				(tracks allowed)
				(vias not_allowed)
				(pads allowed)
				(copperpour not_allowed)
				(footprints allowed)
			)
			(placement
				(enabled no)
				(sheetname "")
			)
			(fill
				(thermal_gap 0.5)
				(thermal_bridge_width 0.5)
				(island_removal_mode 0)
			)
			(polygon
				(pts
					(xy 474.091 -120.1928) (xy 474.599 -120.1928) (xy 474.599 -120.5738) (xy 474.091 -120.5738)
				)
			)
		)
	)
	(footprint ""
		(layer "B.Cu")
		(at 210.847432 -83.947 -90)
		(property "Reference" "C6P8"
			(at 0.66167 -3.782568 0)
			(unlocked yes)
			(layer "B.SilkS")
			(effects
				(font
					(size 0.7874 0.5842)
					(thickness 0.1524)
				)
				(justify mirror)
			)
		)
		(property "Value" ""
			(at 0 0 90)
			(layer "B.Fab")
			(effects
				(font
					(size 1.27 1.27)
				)
				(justify mirror)
			)
		)
		(duplicate_pad_numbers_are_jumpers no)
		(fp_line
			(start -2.286 7.366)
			(end -1.600708 7.366)
			(stroke
				(width 0.1524)
				(type default)
			)
			(layer "B.SilkS")
		)
		(fp_line
			(start -2.286 7.366)
			(end -2.286 1.63195)
			(stroke
				(width 0.1524)
				(type default)
			)
			(layer "B.SilkS")
		)
		(fp_line
			(start 2.286 7.366)
			(end 1.60147 7.366)
			(stroke
				(width 0.1524)
				(type default)
			)
			(layer "B.SilkS")
		)
		(fp_line
			(start 2.286 7.366)
			(end 2.286 1.632712)
			(stroke
				(width 0.1524)
				(type default)
			)
			(layer "B.SilkS")
		)
		(fp_line
			(start -2.504948 1.633728)
			(end -1.6002 1.633728)
			(stroke
				(width 0.1524)
				(type default)
			)
			(layer "B.SilkS")
		)
		(fp_line
			(start 2.563114 1.633728)
			(end 1.6002 1.633728)
			(stroke
				(width 0.1524)
				(type default)
			)
			(layer "B.SilkS")
		)
		(fp_line
			(start -2.504948 -1.616456)
			(end -2.504948 1.633728)
			(stroke
				(width 0.1524)
				(type default)
			)
			(layer "B.SilkS")
		)
		(fp_line
			(start -1.6002 -1.616456)
			(end -2.504948 -1.616456)
			(stroke
				(width 0.1524)
				(type default)
			)
			(layer "B.SilkS")
		)
		(fp_line
			(start 1.6002 -1.616456)
			(end 2.563114 -1.616456)
			(stroke
				(width 0.1524)
				(type default)
			)
			(layer "B.SilkS")
		)
		(fp_line
			(start 2.563114 -1.616456)
			(end 2.563114 1.633728)
			(stroke
				(width 0.1524)
				(type default)
			)
			(layer "B.SilkS")
		)
		(fp_rect
			(start 2.286 7.366)
			(end -2.286 -0.254)
			(stroke
				(width 0)
				(type default)
			)
			(fill no)
			(layer "B.CrtYd")
		)
		(fp_line
			(start -2.286 7.366)
			(end 2.286 7.366)
			(stroke
				(width 0.1)
				(type default)
			)
			(layer "B.Fab")
		)
		(fp_line
			(start 2.286 7.366)
			(end 2.286 -0.254)
			(stroke
				(width 0.1)
				(type default)
			)
			(layer "B.Fab")
		)
		(fp_line
			(start -2.286 -0.254)
			(end -2.286 7.366)
			(stroke
				(width 0.1)
				(type default)
			)
			(layer "B.Fab")
		)
		(fp_line
			(start 2.286 -0.254)
			(end -2.286 -0.254)
			(stroke
				(width 0.1)
				(type default)
			)
			(layer "B.Fab")
		)
		(pad "1" smd rect
			(at 0 0 90)
			(size 2.54 3.048)
			(layers "B.Cu" "B.Mask" "B.Paste")
			(net "PVCCIN_CPU0")
		)
		(pad "2" smd rect
			(at 0 7.112 90)
			(size 2.54 3.048)
			(layers "B.Cu" "B.Mask" "B.Paste")
			(net "GND")
		)
	)
	(footprint ""
		(layer "B.Cu")
		(at 376.174 -66.929)
		(property "Reference" "R2R4"
			(at 0 0 0)
			(layer "B.SilkS")
			(hide yes)
			(effects
				(font
					(size 1.27 1.27)
				)
				(justify mirror)
			)
		)
		(property "Value" ""
			(at 0 0 0)
			(layer "B.Fab")
			(effects
				(font
					(size 1.27 1.27)
				)
				(justify mirror)
			)
		)
		(duplicate_pad_numbers_are_jumpers no)
		(fp_poly
			(pts
				(xy 0.2794 -0.1016) (xy -0.2794 -0.1016) (xy -0.2794 0.9906) (xy 0.2794 0.9906)
			)
			(stroke
				(width 0)
				(type default)
			)
			(fill no)
			(layer "B.CrtYd")
		)
		(fp_line
			(start -0.2794 -0.1016)
			(end 0.2794 -0.1016)
			(stroke
				(width 0.1)
				(type default)
			)
			(layer "B.Fab")
		)
		(fp_line
			(start -0.2794 0.9906)
			(end -0.2794 -0.1016)
			(stroke
				(width 0.1)
				(type default)
			)
			(layer "B.Fab")
		)
		(fp_line
			(start 0.2794 -0.1016)
			(end 0.2794 0.9906)
			(stroke
				(width 0.1)
				(type default)
			)
			(layer "B.Fab")
		)
		(fp_line
			(start 0.2794 0.9906)
			(end -0.2794 0.9906)
			(stroke
				(width 0.1)
				(type default)
			)
			(layer "B.Fab")
		)
		(pad "1" smd rect
			(at 0 0 180)
			(size 0.508 0.508)
			(layers "B.Cu" "B.Mask" "B.Paste")
			(net "FM_ADR_SMI_GPIO_R_N")
		)
		(pad "2" smd rect
			(at 0 0.889 180)
			(size 0.508 0.508)
			(layers "B.Cu" "B.Mask" "B.Paste")
			(net "FM_ADR_SMI_GPIO_N")
		)
		(zone
			(layer "B.Cu")
			(hatch none 0.5)
			(connect_pads
				(clearance 0)
			)
			(min_thickness 0.25)
			(keepout
				(tracks allowed)
				(vias not_allowed)
				(pads allowed)
				(copperpour not_allowed)
				(footprints allowed)
			)
			(placement
				(enabled no)
				(sheetname "")
			)
			(fill
				(thermal_gap 0.5)
				(thermal_bridge_width 0.5)
				(island_removal_mode 0)
			)
			(polygon
				(pts
					(xy 376.428 -66.675) (xy 375.92 -66.675) (xy 375.92 -66.294) (xy 376.428 -66.294)
				)
			)
		)
		(zone
			(layer "B.Cu")
			(hatch none 0.5)
			(connect_pads
				(clearance 0)
			)
			(min_thickness 0.25)
			(keepout
				(tracks not_allowed)
				(vias allowed)
				(pads allowed)
				(copperpour not_allowed)
				(footprints allowed)
			)
			(placement
				(enabled no)
				(sheetname "")
			)
			(fill
				(thermal_gap 0.5)
				(thermal_bridge_width 0.5)
				(island_removal_mode 0)
			)
			(polygon
				(pts
					(xy 376.428 -66.294) (xy 375.92 -66.294) (xy 375.92 -66.675) (xy 376.428 -66.675)
				)
			)
		)
	)
	(footprint ""
		(layer "B.Cu")
		(at 380.3904 -43.7515)
		(property "Reference" "Q7E8"
			(at 1.28143 0.59944 90)
			(unlocked yes)
			(layer "B.SilkS")
			(effects
				(font
					(size 0.7874 0.5842)
					(thickness 0.1524)
				)
				(justify left mirror)
			)
		)
		(property "Value" ""
			(at 0 0 0)
			(layer "B.Fab")
			(effects
				(font
					(size 1.27 1.27)
				)
				(justify mirror)
			)
		)
		(duplicate_pad_numbers_are_jumpers no)
		(fp_line
			(start -1.778 -0.5715)
			(end -1.778 0.3175)
			(stroke
				(width 0.1524)
				(type default)
			)
			(layer "B.SilkS")
		)
		(fp_line
			(start -1.778 2.4765)
			(end -1.778 1.5875)
			(stroke
				(width 0.1524)
				(type default)
			)
			(layer "B.SilkS")
		)
		(fp_line
			(start -0.9525 -0.5715)
			(end -1.778 -0.5715)
			(stroke
				(width 0.1524)
				(type default)
			)
			(layer "B.SilkS")
		)
		(fp_line
			(start -0.9525 2.4765)
			(end -1.778 2.4765)
			(stroke
				(width 0.1524)
				(type default)
			)
			(layer "B.SilkS")
		)
		(fp_line
			(start -0.381 0.635)
			(end -0.381 1.27)
			(stroke
				(width 0.1524)
				(type default)
			)
			(layer "B.SilkS")
		)
		(fp_circle
			(center 0.9525 -0.9271)
			(end 1.0795 -0.9271)
			(stroke
				(width 0.254)
				(type default)
			)
			(fill no)
			(layer "B.SilkS")
		)
		(fp_poly
			(pts
				(xy -1.778 2.4765) (xy -0.381 2.4765) (xy -0.381 -0.5715) (xy -1.778 -0.5715)
			)
			(stroke
				(width 0)
				(type default)
			)
			(fill no)
			(layer "B.CrtYd")
		)
		(fp_line
			(start -1.778 -0.5715)
			(end -0.381 -0.5715)
			(stroke
				(width 0.1)
				(type default)
			)
			(layer "B.Fab")
		)
		(fp_line
			(start -1.778 2.4765)
			(end -1.778 -0.5715)
			(stroke
				(width 0.1)
				(type default)
			)
			(layer "B.Fab")
		)
		(fp_line
			(start -0.381 -0.5715)
			(end -0.381 2.4765)
			(stroke
				(width 0.1)
				(type default)
			)
			(layer "B.Fab")
		)
		(fp_line
			(start -0.381 2.4765)
			(end -1.778 2.4765)
			(stroke
				(width 0.1)
				(type default)
			)
			(layer "B.Fab")
		)
		(fp_circle
			(center 0.9525 -0.9271)
			(end 1.0795 -0.9271)
			(stroke
				(width 0.254)
				(type default)
			)
			(fill no)
			(layer "B.Fab")
		)
		(pad "1" smd rect
			(at 0 0 180)
			(size 1.143 0.508)
			(layers "B.Cu" "B.Mask" "B.Paste")
			(net "FM_SYS_THROTTLE_LVC3")
		)
		(pad "2" smd rect
			(at 0 1.905 180)
			(size 1.143 0.508)
			(layers "B.Cu" "B.Mask" "B.Paste")
			(net "GND")
		)
		(pad "3" smd rect
			(at -2.159 0.9525 180)
			(size 1.143 0.508)
			(layers "B.Cu" "B.Mask" "B.Paste")
			(net "FM_PWRBRK_N")
		)
	)
)
